(kicad_pcb
	(version 20260206)
	(generator "pcbnew")
	(generator_version "10.0")
	(general
		(thickness 1.6)
		(legacy_teardrops no)
	)
	(paper "A4")
	(title_block
		(title "01162023_DA0F0TEBIF0_F0T_Expander_BD_F_brd_V02_OCP.brd")
		(comment 1 "Grand Teton / footprints 5162-5167 of 9728")
	)
	(layers
		(0 "F.Cu" signal "TOP")
		(4 "In1.Cu" signal "GND")
		(6 "In2.Cu" signal "VCC")
		(8 "In3.Cu" signal "VCC1")
		(10 "In4.Cu" signal "GND1")
		(12 "In5.Cu" signal "IN1")
		(14 "In6.Cu" signal "GND2")
		(16 "In7.Cu" signal "IN2")
		(18 "In8.Cu" signal "GND3")
		(20 "In9.Cu" signal "IN3")
		(22 "In10.Cu" signal "GND4")
		(24 "In11.Cu" signal "IN4")
		(26 "In12.Cu" signal "GND5")
		(28 "In13.Cu" signal "IN5")
		(30 "In14.Cu" signal "GND6")
		(32 "In15.Cu" signal "IN6")
		(34 "In16.Cu" signal "GND7")
		(2 "B.Cu" signal "BOTTOM")
		(9 "F.Adhes" user "F.Adhesive")
		(11 "B.Adhes" user "B.Adhesive")
		(13 "F.Paste" user "Package Geometry/Pastemask Top")
		(15 "B.Paste" user "Package Geometry/Pastemask Bottom")
		(5 "F.SilkS" user "Ref Des/Silkscreen Top")
		(7 "B.SilkS" user "Ref Des/Silkscreen Bottom")
		(1 "F.Mask" user "Board Geometry/Soldermask Top")
		(3 "B.Mask" user "Board Geometry/Soldermask Bottom")
		(17 "Dwgs.User" user "User.Drawings")
		(19 "Cmts.User" user "User.Comments")
		(21 "Eco1.User" user "User.Eco1")
		(23 "Eco2.User" user "User.Eco2")
		(25 "Edge.Cuts" user "Board Geometry/Outline")
		(27 "Margin" user)
		(31 "F.CrtYd" user "Package Geometry/Place Bound Top")
		(29 "B.CrtYd" user "Package Geometry/Place Bound Bottom")
		(35 "F.Fab" user "Ref Des/Assembly Top")
		(33 "B.Fab" user "Ref Des/Assembly Bottom")
	)
	(footprint ""
		(layer "F.Cu")
		(at 241.600736 -203.005182)
		(property "Reference" "R6150"
			(at 0 0 0)
			(layer "F.SilkS")
			(hide yes)
			(effects
				(font
					(size 1.27 1.27)
				)
			)
		)
		(property "Value" ""
			(at 0 0 0)
			(layer "F.Fab")
			(effects
				(font
					(size 1.27 1.27)
				)
			)
		)
		(duplicate_pad_numbers_are_jumpers no)
		(fp_line
			(start -0.7874 -0.4064)
			(end 0.7874 -0.4064)
			(stroke
				(width 0.1524)
				(type default)
			)
			(layer "F.SilkS")
		)
		(fp_line
			(start -0.7874 0.4064)
			(end -0.7874 -0.4064)
			(stroke
				(width 0.1524)
				(type default)
			)
			(layer "F.SilkS")
		)
		(fp_line
			(start 0.7874 -0.4064)
			(end 0.7874 0.4064)
			(stroke
				(width 0.1524)
				(type default)
			)
			(layer "F.SilkS")
		)
		(fp_line
			(start 0.7874 0.4064)
			(end -0.7874 0.4064)
			(stroke
				(width 0.1524)
				(type default)
			)
			(layer "F.SilkS")
		)
		(fp_line
			(start -0.67945 -0.305054)
			(end -0.12065 -0.305054)
			(stroke
				(width 0.1)
				(type default)
			)
			(layer "F.Fab")
		)
		(fp_line
			(start -0.67945 0.3048)
			(end -0.67945 -0.305054)
			(stroke
				(width 0.1)
				(type default)
			)
			(layer "F.Fab")
		)
		(fp_line
			(start -0.12065 -0.305054)
			(end -0.12065 -0.2794)
			(stroke
				(width 0.1)
				(type default)
			)
			(layer "F.Fab")
		)
		(fp_line
			(start -0.12065 -0.2794)
			(end 0.12065 -0.2794)
			(stroke
				(width 0.1)
				(type default)
			)
			(layer "F.Fab")
		)
		(fp_line
			(start -0.12065 0.2794)
			(end -0.12065 0.3048)
			(stroke
				(width 0.1)
				(type default)
			)
			(layer "F.Fab")
		)
		(fp_line
			(start -0.12065 0.3048)
			(end -0.67945 0.3048)
			(stroke
				(width 0.1)
				(type default)
			)
			(layer "F.Fab")
		)
		(fp_line
			(start 0.120396 0.2794)
			(end -0.12065 0.2794)
			(stroke
				(width 0.1)
				(type default)
			)
			(layer "F.Fab")
		)
		(fp_line
			(start 0.120396 0.3048)
			(end 0.120396 0.2794)
			(stroke
				(width 0.1)
				(type default)
			)
			(layer "F.Fab")
		)
		(fp_line
			(start 0.12065 -0.3048)
			(end 0.67945 -0.3048)
			(stroke
				(width 0.1)
				(type default)
			)
			(layer "F.Fab")
		)
		(fp_line
			(start 0.12065 -0.2794)
			(end 0.12065 -0.3048)
			(stroke
				(width 0.1)
				(type default)
			)
			(layer "F.Fab")
		)
		(fp_line
			(start 0.67945 -0.3048)
			(end 0.67945 0.3048)
			(stroke
				(width 0.1)
				(type default)
			)
			(layer "F.Fab")
		)
		(fp_line
			(start 0.67945 0.3048)
			(end 0.120396 0.3048)
			(stroke
				(width 0.1)
				(type default)
			)
			(layer "F.Fab")
		)
		(pad "1" smd circle
			(at -0.40005 0)
			(size 0 0)
			(layers "F.Cu" "F.Mask" "F.Paste")
			(net "BIC_FWSPIDQ3")
		)
		(pad "2" smd circle
			(at 0.40005 0)
			(size 0 0)
			(layers "F.Cu" "F.Mask" "F.Paste")
			(net "P3V3_AUX")
		)
	)
	(footprint ""
		(layer "F.Cu")
		(at 452.543672 -46.90491)
		(property "Reference" "R674"
			(at 0 0 0)
			(layer "F.SilkS")
			(hide yes)
			(effects
				(font
					(size 1.27 1.27)
				)
			)
		)
		(property "Value" ""
			(at 0 0 0)
			(layer "F.Fab")
			(effects
				(font
					(size 1.27 1.27)
				)
			)
		)
		(duplicate_pad_numbers_are_jumpers no)
		(fp_line
			(start -0.7874 -0.4064)
			(end 0.7874 -0.4064)
			(stroke
				(width 0.1524)
				(type default)
			)
			(layer "F.SilkS")
		)
		(fp_line
			(start -0.7874 0.4064)
			(end -0.7874 -0.4064)
			(stroke
				(width 0.1524)
				(type default)
			)
			(layer "F.SilkS")
		)
		(fp_line
			(start 0.7874 -0.4064)
			(end 0.7874 0.4064)
			(stroke
				(width 0.1524)
				(type default)
			)
			(layer "F.SilkS")
		)
		(fp_line
			(start 0.7874 0.4064)
			(end -0.7874 0.4064)
			(stroke
				(width 0.1524)
				(type default)
			)
			(layer "F.SilkS")
		)
		(fp_line
			(start -0.67945 -0.305054)
			(end -0.12065 -0.305054)
			(stroke
				(width 0.1)
				(type default)
			)
			(layer "F.Fab")
		)
		(fp_line
			(start -0.67945 0.3048)
			(end -0.67945 -0.305054)
			(stroke
				(width 0.1)
				(type default)
			)
			(layer "F.Fab")
		)
		(fp_line
			(start -0.12065 -0.305054)
			(end -0.12065 -0.2794)
			(stroke
				(width 0.1)
				(type default)
			)
			(layer "F.Fab")
		)
		(fp_line
			(start -0.12065 -0.2794)
			(end 0.12065 -0.2794)
			(stroke
				(width 0.1)
				(type default)
			)
			(layer "F.Fab")
		)
		(fp_line
			(start -0.12065 0.2794)
			(end -0.12065 0.3048)
			(stroke
				(width 0.1)
				(type default)
			)
			(layer "F.Fab")
		)
		(fp_line
			(start -0.12065 0.3048)
			(end -0.67945 0.3048)
			(stroke
				(width 0.1)
				(type default)
			)
			(layer "F.Fab")
		)
		(fp_line
			(start 0.120396 0.2794)
			(end -0.12065 0.2794)
			(stroke
				(width 0.1)
				(type default)
			)
			(layer "F.Fab")
		)
		(fp_line
			(start 0.120396 0.3048)
			(end 0.120396 0.2794)
			(stroke
				(width 0.1)
				(type default)
			)
			(layer "F.Fab")
		)
		(fp_line
			(start 0.12065 -0.3048)
			(end 0.67945 -0.3048)
			(stroke
				(width 0.1)
				(type default)
			)
			(layer "F.Fab")
		)
		(fp_line
			(start 0.12065 -0.2794)
			(end 0.12065 -0.3048)
			(stroke
				(width 0.1)
				(type default)
			)
			(layer "F.Fab")
		)
		(fp_line
			(start 0.67945 -0.3048)
			(end 0.67945 0.3048)
			(stroke
				(width 0.1)
				(type default)
			)
			(layer "F.Fab")
		)
		(fp_line
			(start 0.67945 0.3048)
			(end 0.120396 0.3048)
			(stroke
				(width 0.1)
				(type default)
			)
			(layer "F.Fab")
		)
		(pad "1" smd circle
			(at -0.40005 0)
			(size 0 0)
			(layers "F.Cu" "F.Mask" "F.Paste")
			(net "SSD15_ADC_ALERT_N")
		)
		(pad "2" smd circle
			(at 0.40005 0)
			(size 0 0)
			(layers "F.Cu" "F.Mask" "F.Paste")
			(net "SSD_8_15_ADC_ALERT_N")
		)
	)
	(footprint ""
		(layer "F.Cu")
		(at 454.896982 -117.627654 180)
		(property "Reference" "PR7050"
			(at 0 0 180)
			(layer "F.SilkS")
			(hide yes)
			(effects
				(font
					(size 1.27 1.27)
				)
			)
		)
		(property "Value" ""
			(at 0 0 180)
			(layer "F.Fab")
			(effects
				(font
					(size 1.27 1.27)
				)
			)
		)
		(duplicate_pad_numbers_are_jumpers no)
		(fp_line
			(start 0.7874 0.4064)
			(end -0.7874 0.4064)
			(stroke
				(width 0.1524)
				(type default)
			)
			(layer "F.SilkS")
		)
		(fp_line
			(start 0.7874 -0.4064)
			(end 0.7874 0.4064)
			(stroke
				(width 0.1524)
				(type default)
			)
			(layer "F.SilkS")
		)
		(fp_line
			(start -0.7874 0.4064)
			(end -0.7874 -0.4064)
			(stroke
				(width 0.1524)
				(type default)
			)
			(layer "F.SilkS")
		)
		(fp_line
			(start -0.7874 -0.4064)
			(end 0.7874 -0.4064)
			(stroke
				(width 0.1524)
				(type default)
			)
			(layer "F.SilkS")
		)
		(fp_line
			(start 0.67945 0.3048)
			(end 0.120396 0.3048)
			(stroke
				(width 0.1)
				(type default)
			)
			(layer "F.Fab")
		)
		(fp_line
			(start 0.67945 -0.3048)
			(end 0.67945 0.3048)
			(stroke
				(width 0.1)
				(type default)
			)
			(layer "F.Fab")
		)
		(fp_line
			(start 0.12065 -0.2794)
			(end 0.12065 -0.3048)
			(stroke
				(width 0.1)
				(type default)
			)
			(layer "F.Fab")
		)
		(fp_line
			(start 0.12065 -0.3048)
			(end 0.67945 -0.3048)
			(stroke
				(width 0.1)
				(type default)
			)
			(layer "F.Fab")
		)
		(fp_line
			(start 0.120396 0.3048)
			(end 0.120396 0.2794)
			(stroke
				(width 0.1)
				(type default)
			)
			(layer "F.Fab")
		)
		(fp_line
			(start 0.120396 0.2794)
			(end -0.12065 0.2794)
			(stroke
				(width 0.1)
				(type default)
			)
			(layer "F.Fab")
		)
		(fp_line
			(start -0.12065 0.3048)
			(end -0.67945 0.3048)
			(stroke
				(width 0.1)
				(type default)
			)
			(layer "F.Fab")
		)
		(fp_line
			(start -0.12065 0.2794)
			(end -0.12065 0.3048)
			(stroke
				(width 0.1)
				(type default)
			)
			(layer "F.Fab")
		)
		(fp_line
			(start -0.12065 -0.2794)
			(end 0.12065 -0.2794)
			(stroke
				(width 0.1)
				(type default)
			)
			(layer "F.Fab")
		)
		(fp_line
			(start -0.12065 -0.305054)
			(end -0.12065 -0.2794)
			(stroke
				(width 0.1)
				(type default)
			)
			(layer "F.Fab")
		)
		(fp_line
			(start -0.67945 0.3048)
			(end -0.67945 -0.305054)
			(stroke
				(width 0.1)
				(type default)
			)
			(layer "F.Fab")
		)
		(fp_line
			(start -0.67945 -0.305054)
			(end -0.12065 -0.305054)
			(stroke
				(width 0.1)
				(type default)
			)
			(layer "F.Fab")
		)
		(pad "1" smd circle
			(at -0.40005 0 180)
			(size 0 0)
			(layers "F.Cu" "F.Mask" "F.Paste")
			(net "P12V_NIC7_CO_OV_FB")
		)
		(pad "2" smd circle
			(at 0.40005 0 180)
			(size 0 0)
			(layers "F.Cu" "F.Mask" "F.Paste")
			(net "P12V_NIC7_R")
		)
	)
	(footprint ""
		(layer "F.Cu")
		(at 440.58332 -113.628678)
		(property "Reference" "PC908"
			(at 0 0 0)
			(layer "F.SilkS")
			(hide yes)
			(effects
				(font
					(size 1.27 1.27)
				)
			)
		)
		(property "Value" ""
			(at 0 0 0)
			(layer "F.Fab")
			(effects
				(font
					(size 1.27 1.27)
				)
			)
		)
		(duplicate_pad_numbers_are_jumpers no)
		(fp_line
			(start -0.7874 -0.4064)
			(end 0.7874 -0.4064)
			(stroke
				(width 0.1524)
				(type default)
			)
			(layer "F.SilkS")
		)
		(fp_line
			(start -0.7874 0.4064)
			(end -0.7874 -0.4064)
			(stroke
				(width 0.1524)
				(type default)
			)
			(layer "F.SilkS")
		)
		(fp_line
			(start 0.7874 -0.4064)
			(end 0.7874 0.4064)
			(stroke
				(width 0.1524)
				(type default)
			)
			(layer "F.SilkS")
		)
		(fp_line
			(start 0.7874 0.4064)
			(end -0.7874 0.4064)
			(stroke
				(width 0.1524)
				(type default)
			)
			(layer "F.SilkS")
		)
		(fp_line
			(start -0.67945 -0.305054)
			(end -0.12065 -0.305054)
			(stroke
				(width 0.1)
				(type default)
			)
			(layer "F.Fab")
		)
		(fp_line
			(start -0.67945 0.3048)
			(end -0.67945 -0.305054)
			(stroke
				(width 0.1)
				(type default)
			)
			(layer "F.Fab")
		)
		(fp_line
			(start -0.12065 -0.305054)
			(end -0.12065 -0.2794)
			(stroke
				(width 0.1)
				(type default)
			)
			(layer "F.Fab")
		)
		(fp_line
			(start -0.12065 -0.2794)
			(end 0.12065 -0.2794)
			(stroke
				(width 0.1)
				(type default)
			)
			(layer "F.Fab")
		)
		(fp_line
			(start -0.12065 0.2794)
			(end -0.12065 0.3048)
			(stroke
				(width 0.1)
				(type default)
			)
			(layer "F.Fab")
		)
		(fp_line
			(start -0.12065 0.3048)
			(end -0.67945 0.3048)
			(stroke
				(width 0.1)
				(type default)
			)
			(layer "F.Fab")
		)
		(fp_line
			(start 0.120396 0.2794)
			(end -0.12065 0.2794)
			(stroke
				(width 0.1)
				(type default)
			)
			(layer "F.Fab")
		)
		(fp_line
			(start 0.120396 0.3048)
			(end 0.120396 0.2794)
			(stroke
				(width 0.1)
				(type default)
			)
			(layer "F.Fab")
		)
		(fp_line
			(start 0.12065 -0.3048)
			(end 0.67945 -0.3048)
			(stroke
				(width 0.1)
				(type default)
			)
			(layer "F.Fab")
		)
		(fp_line
			(start 0.12065 -0.2794)
			(end 0.12065 -0.3048)
			(stroke
				(width 0.1)
				(type default)
			)
			(layer "F.Fab")
		)
		(fp_line
			(start 0.67945 -0.3048)
			(end 0.67945 0.3048)
			(stroke
				(width 0.1)
				(type default)
			)
			(layer "F.Fab")
		)
		(fp_line
			(start 0.67945 0.3048)
			(end 0.120396 0.3048)
			(stroke
				(width 0.1)
				(type default)
			)
			(layer "F.Fab")
		)
		(pad "1" smd circle
			(at -0.40005 0)
			(size 0 0)
			(layers "F.Cu" "F.Mask" "F.Paste")
			(net "P3V3_AUX")
		)
		(pad "2" smd circle
			(at 0.40005 0)
			(size 0 0)
			(layers "F.Cu" "F.Mask" "F.Paste")
			(net "GND")
		)
	)
	(footprint ""
		(layer "F.Cu")
		(at 386.90804 -163.061396 180)
		(property "Reference" "R310"
			(at 0 0 180)
			(layer "F.SilkS")
			(hide yes)
			(effects
				(font
					(size 1.27 1.27)
				)
			)
		)
		(property "Value" ""
			(at 0 0 180)
			(layer "F.Fab")
			(effects
				(font
					(size 1.27 1.27)
				)
			)
		)
		(duplicate_pad_numbers_are_jumpers no)
		(fp_line
			(start 0.7874 0.4064)
			(end -0.7874 0.4064)
			(stroke
				(width 0.1524)
				(type default)
			)
			(layer "F.SilkS")
		)
		(fp_line
			(start 0.7874 -0.4064)
			(end 0.7874 0.4064)
			(stroke
				(width 0.1524)
				(type default)
			)
			(layer "F.SilkS")
		)
		(fp_line
			(start -0.7874 0.4064)
			(end -0.7874 -0.4064)
			(stroke
				(width 0.1524)
				(type default)
			)
			(layer "F.SilkS")
		)
		(fp_line
			(start -0.7874 -0.4064)
			(end 0.7874 -0.4064)
			(stroke
				(width 0.1524)
				(type default)
			)
			(layer "F.SilkS")
		)
		(fp_line
			(start 0.67945 0.3048)
			(end 0.120396 0.3048)
			(stroke
				(width 0.1)
				(type default)
			)
			(layer "F.Fab")
		)
		(fp_line
			(start 0.67945 -0.3048)
			(end 0.67945 0.3048)
			(stroke
				(width 0.1)
				(type default)
			)
			(layer "F.Fab")
		)
		(fp_line
			(start 0.12065 -0.2794)
			(end 0.12065 -0.3048)
			(stroke
				(width 0.1)
				(type default)
			)
			(layer "F.Fab")
		)
		(fp_line
			(start 0.12065 -0.3048)
			(end 0.67945 -0.3048)
			(stroke
				(width 0.1)
				(type default)
			)
			(layer "F.Fab")
		)
		(fp_line
			(start 0.120396 0.3048)
			(end 0.120396 0.2794)
			(stroke
				(width 0.1)
				(type default)
			)
			(layer "F.Fab")
		)
		(fp_line
			(start 0.120396 0.2794)
			(end -0.12065 0.2794)
			(stroke
				(width 0.1)
				(type default)
			)
			(layer "F.Fab")
		)
		(fp_line
			(start -0.12065 0.3048)
			(end -0.67945 0.3048)
			(stroke
				(width 0.1)
				(type default)
			)
			(layer "F.Fab")
		)
		(fp_line
			(start -0.12065 0.2794)
			(end -0.12065 0.3048)
			(stroke
				(width 0.1)
				(type default)
			)
			(layer "F.Fab")
		)
		(fp_line
			(start -0.12065 -0.2794)
			(end 0.12065 -0.2794)
			(stroke
				(width 0.1)
				(type default)
			)
			(layer "F.Fab")
		)
		(fp_line
			(start -0.12065 -0.305054)
			(end -0.12065 -0.2794)
			(stroke
				(width 0.1)
				(type default)
			)
			(layer "F.Fab")
		)
		(fp_line
			(start -0.67945 0.3048)
			(end -0.67945 -0.305054)
			(stroke
				(width 0.1)
				(type default)
			)
			(layer "F.Fab")
		)
		(fp_line
			(start -0.67945 -0.305054)
			(end -0.12065 -0.305054)
			(stroke
				(width 0.1)
				(type default)
			)
			(layer "F.Fab")
		)
		(pad "1" smd circle
			(at -0.40005 0 180)
			(size 0 0)
			(layers "F.Cu" "F.Mask" "F.Paste")
			(net "PWRGD_NIC6_PWR_GOOD")
		)
		(pad "2" smd circle
			(at 0.40005 0 180)
			(size 0 0)
			(layers "F.Cu" "F.Mask" "F.Paste")
			(net "PWRGD_NIC6_PWR_GOOD_R")
		)
	)
	(footprint ""
		(layer "F.Cu")
		(at 139.768072 -18.437098)
		(property "Reference" "R1665"
			(at 0 0 0)
			(layer "F.SilkS")
			(hide yes)
			(effects
				(font
					(size 1.27 1.27)
				)
			)
		)
		(property "Value" ""
			(at 0 0 0)
			(layer "F.Fab")
			(effects
				(font
					(size 1.27 1.27)
				)
			)
		)
		(duplicate_pad_numbers_are_jumpers no)
		(fp_line
			(start -0.7874 -0.4064)
			(end 0.7874 -0.4064)
			(stroke
				(width 0.1524)
				(type default)
			)
			(layer "F.SilkS")
		)
		(fp_line
			(start -0.7874 0.4064)
			(end -0.7874 -0.4064)
			(stroke
				(width 0.1524)
				(type default)
			)
			(layer "F.SilkS")
		)
		(fp_line
			(start 0.7874 -0.4064)
			(end 0.7874 0.4064)
			(stroke
				(width 0.1524)
				(type default)
			)
			(layer "F.SilkS")
		)
		(fp_line
			(start 0.7874 0.4064)
			(end -0.7874 0.4064)
			(stroke
				(width 0.1524)
				(type default)
			)
			(layer "F.SilkS")
		)
		(fp_line
			(start -0.67945 -0.305054)
			(end -0.12065 -0.305054)
			(stroke
				(width 0.1)
				(type default)
			)
			(layer "F.Fab")
		)
		(fp_line
			(start -0.67945 0.3048)
			(end -0.67945 -0.305054)
			(stroke
				(width 0.1)
				(type default)
			)
			(layer "F.Fab")
		)
		(fp_line
			(start -0.12065 -0.305054)
			(end -0.12065 -0.2794)
			(stroke
				(width 0.1)
				(type default)
			)
			(layer "F.Fab")
		)
		(fp_line
			(start -0.12065 -0.2794)
			(end 0.12065 -0.2794)
			(stroke
				(width 0.1)
				(type default)
			)
			(layer "F.Fab")
		)
		(fp_line
			(start -0.12065 0.2794)
			(end -0.12065 0.3048)
			(stroke
				(width 0.1)
				(type default)
			)
			(layer "F.Fab")
		)
		(fp_line
			(start -0.12065 0.3048)
			(end -0.67945 0.3048)
			(stroke
				(width 0.1)
				(type default)
			)
			(layer "F.Fab")
		)
		(fp_line
			(start 0.120396 0.2794)
			(end -0.12065 0.2794)
			(stroke
				(width 0.1)
				(type default)
			)
			(layer "F.Fab")
		)
		(fp_line
			(start 0.120396 0.3048)
			(end 0.120396 0.2794)
			(stroke
				(width 0.1)
				(type default)
			)
			(layer "F.Fab")
		)
		(fp_line
			(start 0.12065 -0.3048)
			(end 0.67945 -0.3048)
			(stroke
				(width 0.1)
				(type default)
			)
			(layer "F.Fab")
		)
		(fp_line
			(start 0.12065 -0.2794)
			(end 0.12065 -0.3048)
			(stroke
				(width 0.1)
				(type default)
			)
			(layer "F.Fab")
		)
		(fp_line
			(start 0.67945 -0.3048)
			(end 0.67945 0.3048)
			(stroke
				(width 0.1)
				(type default)
			)
			(layer "F.Fab")
		)
		(fp_line
			(start 0.67945 0.3048)
			(end 0.120396 0.3048)
			(stroke
				(width 0.1)
				(type default)
			)
			(layer "F.Fab")
		)
		(pad "1" smd circle
			(at -0.40005 0)
			(size 0 0)
			(layers "F.Cu" "F.Mask" "F.Paste")
			(net "SMB_ISO_SSD4_R_SCL")
		)
		(pad "2" smd circle
			(at 0.40005 0)
			(size 0 0)
			(layers "F.Cu" "F.Mask" "F.Paste")
			(net "SMB_ISO_SSD4_SCL")
		)
	)
)
